# T6G (Grand Teton) — schematic netlist excerpt (pin names and nets, part order shuffled) for the footprints in the layout excerpt that follows; sources: Cadence DE-HDL packaged netlist, KiCad conversion of 04192023_DAF0TMB3IC0_F0TG_MB_C_brd_V02_OCP.brd

R1137  Q_RES  0 5% EMPTY  pkg 0402LF  page 135 : A = HP_LVC3_OCP_V3_1_P12V_PWRGD ; B = P3V3_OCP_EN_1_R2
R2829  Q_RES  100K 1% EMPTY  pkg 0402LF  page 127 : A = RST_BMC_FROM_SWB_N ; B = GND

(kicad_pcb
	(version 20260206)
	(generator "pcbnew")
	(generator_version "10.0")
	(general
		(thickness 1.6)
		(legacy_teardrops no)
	)
	(paper "A4")
	(title_block
		(title "04192023_DAF0TMB3IC0_F0TG_MB_C_brd_V02_OCP.brd")
		(comment 1 "Grand Teton / footprints 4120-4121 of 8354")
	)
	(layers
		(0 "F.Cu" signal "TOP")
		(4 "In1.Cu" signal "GND")
		(6 "In2.Cu" signal "IN1")
		(8 "In3.Cu" signal "GND1")
		(10 "In4.Cu" signal "IN2")
		(12 "In5.Cu" signal "GND2")
		(14 "In6.Cu" signal "IN3")
		(16 "In7.Cu" signal "GND3")
		(18 "In8.Cu" signal "VCC")
		(20 "In9.Cu" signal "VCC1")
		(22 "In10.Cu" signal "GND4")
		(24 "In11.Cu" signal "IN4")
		(26 "In12.Cu" signal "GND5")
		(28 "In13.Cu" signal "IN5")
		(30 "In14.Cu" signal "GND6")
		(32 "In15.Cu" signal "IN6")
		(34 "In16.Cu" signal "GND7")
		(2 "B.Cu" signal "BOTTOM")
		(9 "F.Adhes" user "F.Adhesive")
		(11 "B.Adhes" user "B.Adhesive")
		(13 "F.Paste" user "Package Geometry/Pastemask Top")
		(15 "B.Paste" user "Package Geometry/Pastemask Bottom")
		(5 "F.SilkS" user "Ref Des/Silkscreen Top")
		(7 "B.SilkS" user "Ref Des/Silkscreen Bottom")
		(1 "F.Mask" user "Board Geometry/Soldermask Top")
		(3 "B.Mask" user "Board Geometry/Soldermask Bottom")
		(17 "Dwgs.User" user "User.Drawings")
		(19 "Cmts.User" user "User.Comments")
		(21 "Eco1.User" user "User.Eco1")
		(23 "Eco2.User" user "User.Eco2")
		(25 "Edge.Cuts" user "Board Geometry/Outline")
		(27 "Margin" user)
		(31 "F.CrtYd" user "Package Geometry/Place Bound Top")
		(29 "B.CrtYd" user "Package Geometry/Place Bound Bottom")
		(35 "F.Fab" user "Ref Des/Assembly Top")
		(33 "B.Fab" user "Ref Des/Assembly Bottom")
	)
	(footprint ""
		(layer "F.Cu")
		(at 419.230302 -440.012836 90)
		(property "Reference" "R2829"
			(at 0 0 90)
			(layer "F.SilkS")
			(hide yes)
			(effects
				(font
					(size 1.27 1.27)
				)
			)
		)
		(property "Value" ""
			(at 0 0 90)
			(layer "F.Fab")
			(effects
				(font
					(size 1.27 1.27)
				)
			)
		)
		(duplicate_pad_numbers_are_jumpers no)
		(fp_line
			(start 0.7874 -0.4064)
			(end 0.7874 0.4064)
			(stroke
				(width 0.1524)
				(type default)
			)
			(layer "F.SilkS")
		)
		(fp_line
			(start -0.7874 -0.4064)
			(end 0.7874 -0.4064)
			(stroke
				(width 0.1524)
				(type default)
			)
			(layer "F.SilkS")
		)
		(fp_line
			(start 0.7874 0.4064)
			(end -0.7874 0.4064)
			(stroke
				(width 0.1524)
				(type default)
			)
			(layer "F.SilkS")
		)
		(fp_line
			(start -0.7874 0.4064)
			(end -0.7874 -0.4064)
			(stroke
				(width 0.1524)
				(type default)
			)
			(layer "F.SilkS")
		)
		(fp_line
			(start -0.12065 -0.305054)
			(end -0.12065 -0.2794)
			(stroke
				(width 0.1)
				(type default)
			)
			(layer "F.Fab")
		)
		(fp_line
			(start -0.67945 -0.305054)
			(end -0.12065 -0.305054)
			(stroke
				(width 0.1)
				(type default)
			)
			(layer "F.Fab")
		)
		(fp_line
			(start 0.67945 -0.3048)
			(end 0.67945 0.3048)
			(stroke
				(width 0.1)
				(type default)
			)
			(layer "F.Fab")
		)
		(fp_line
			(start 0.12065 -0.3048)
			(end 0.67945 -0.3048)
			(stroke
				(width 0.1)
				(type default)
			)
			(layer "F.Fab")
		)
		(fp_line
			(start 0.12065 -0.2794)
			(end 0.12065 -0.3048)
			(stroke
				(width 0.1)
				(type default)
			)
			(layer "F.Fab")
		)
		(fp_line
			(start -0.12065 -0.2794)
			(end 0.12065 -0.2794)
			(stroke
				(width 0.1)
				(type default)
			)
			(layer "F.Fab")
		)
		(fp_line
			(start 0.120396 0.2794)
			(end -0.12065 0.2794)
			(stroke
				(width 0.1)
				(type default)
			)
			(layer "F.Fab")
		)
		(fp_line
			(start -0.12065 0.2794)
			(end -0.12065 0.3048)
			(stroke
				(width 0.1)
				(type default)
			)
			(layer "F.Fab")
		)
		(fp_line
			(start 0.67945 0.3048)
			(end 0.120396 0.3048)
			(stroke
				(width 0.1)
				(type default)
			)
			(layer "F.Fab")
		)
		(fp_line
			(start 0.120396 0.3048)
			(end 0.120396 0.2794)
			(stroke
				(width 0.1)
				(type default)
			)
			(layer "F.Fab")
		)
		(fp_line
			(start -0.12065 0.3048)
			(end -0.67945 0.3048)
			(stroke
				(width 0.1)
				(type default)
			)
			(layer "F.Fab")
		)
		(fp_line
			(start -0.67945 0.3048)
			(end -0.67945 -0.305054)
			(stroke
				(width 0.1)
				(type default)
			)
			(layer "F.Fab")
		)
		(pad "1" smd circle
			(at -0.40005 0 90)
			(size 0 0)
			(layers "F.Cu" "F.Mask" "F.Paste")
			(net "RST_BMC_FROM_SWB_N")
		)
		(pad "2" smd circle
			(at 0.40005 0 90)
			(size 0 0)
			(layers "F.Cu" "F.Mask" "F.Paste")
			(net "GND")
		)
	)
	(footprint ""
		(layer "F.Cu")
		(at 421.01643 -109.231176 -90)
		(property "Reference" "R1137"
			(at 0 0 270)
			(layer "F.SilkS")
			(hide yes)
			(effects
				(font
					(size 1.27 1.27)
				)
			)
		)
		(property "Value" ""
			(at 0 0 270)
			(layer "F.Fab")
			(effects
				(font
					(size 1.27 1.27)
				)
			)
		)
		(duplicate_pad_numbers_are_jumpers no)
		(fp_line
			(start -0.7874 0.4064)
			(end -0.7874 -0.4064)
			(stroke
				(width 0.1524)
				(type default)
			)
			(layer "F.SilkS")
		)
		(fp_line
			(start 0.7874 0.4064)
			(end -0.7874 0.4064)
			(stroke
				(width 0.1524)
				(type default)
			)
			(layer "F.SilkS")
		)
		(fp_line
			(start -0.7874 -0.4064)
			(end 0.7874 -0.4064)
			(stroke
				(width 0.1524)
				(type default)
			)
			(layer "F.SilkS")
		)
		(fp_line
			(start 0.7874 -0.4064)
			(end 0.7874 0.4064)
			(stroke
				(width 0.1524)
				(type default)
			)
			(layer "F.SilkS")
		)
		(fp_line
			(start -0.67945 0.3048)
			(end -0.67945 -0.305054)
			(stroke
				(width 0.1)
				(type default)
			)
			(layer "F.Fab")
		)
		(fp_line
			(start -0.12065 0.3048)
			(end -0.67945 0.3048)
			(stroke
				(width 0.1)
				(type default)
			)
			(layer "F.Fab")
		)
		(fp_line
			(start 0.120396 0.3048)
			(end 0.120396 0.2794)
			(stroke
				(width 0.1)
				(type default)
			)
			(layer "F.Fab")
		)
		(fp_line
			(start 0.67945 0.3048)
			(end 0.120396 0.3048)
			(stroke
				(width 0.1)
				(type default)
			)
			(layer "F.Fab")
		)
		(fp_line
			(start -0.12065 0.2794)
			(end -0.12065 0.3048)
			(stroke
				(width 0.1)
				(type default)
			)
			(layer "F.Fab")
		)
		(fp_line
			(start 0.120396 0.2794)
			(end -0.12065 0.2794)
			(stroke
				(width 0.1)
				(type default)
			)
			(layer "F.Fab")
		)
		(fp_line
			(start -0.12065 -0.2794)
			(end 0.12065 -0.2794)
			(stroke
				(width 0.1)
				(type default)
			)
			(layer "F.Fab")
		)
		(fp_line
			(start 0.12065 -0.2794)
			(end 0.12065 -0.3048)
			(stroke
				(width 0.1)
				(type default)
			)
			(layer "F.Fab")
		)
		(fp_line
			(start 0.12065 -0.3048)
			(end 0.67945 -0.3048)
			(stroke
				(width 0.1)
				(type default)
			)
			(layer "F.Fab")
		)
		(fp_line
			(start 0.67945 -0.3048)
			(end 0.67945 0.3048)
			(stroke
				(width 0.1)
				(type default)
			)
			(layer "F.Fab")
		)
		(fp_line
			(start -0.67945 -0.305054)
			(end -0.12065 -0.305054)
			(stroke
				(width 0.1)
				(type default)
			)
			(layer "F.Fab")
		)
		(fp_line
			(start -0.12065 -0.305054)
			(end -0.12065 -0.2794)
			(stroke
				(width 0.1)
				(type default)
			)
			(layer "F.Fab")
		)
		(pad "1" smd circle
			(at -0.40005 0 270)
			(size 0 0)
			(layers "F.Cu" "F.Mask" "F.Paste")
			(net "HP_LVC3_OCP_V3_1_P12V_PWRGD")
		)
		(pad "2" smd circle
			(at 0.40005 0 270)
			(size 0 0)
			(layers "F.Cu" "F.Mask" "F.Paste")
			(net "P3V3_OCP_EN_1_R2")
		)
	)
)
